FILE_TYPE = MACRO_DRAWING;
SET COLOR_WIRE YELLOW;
SET COLOR_PROP ORANGE;
SET COLOR_DOT WHITE;
SET COLOR_ARC YELLOW;
SET COLOR_BODY GREEN;
SET COLOR_NOTE PURPLE;
SET PROP_DISPLAY VALUE;
SET PAGE_NUMBER P387;
FORCEADD P1V0..1
(-4925 5375);
FORCEPROP 3 LASTPIN (-4925 5325) SIG_NAME P1V8_CPU0_RT_1D\g
J 0
(-4915 5335);
DISPLAY 0.659574 (-4915 5335);
PAINT MONO (-4915 5335);
DISPLAY INVISIBLE (-4915 5335);
FORCEPROP 1 LAST HDL_POWER P1V8_CPU0_RT_1D
J 1
(-4925 5425);
DISPLAY 0.489362 (-4925 5425);
PAINT SKYBLUE (-4925 5425);
FORCEPROP 2 LAST CDS_LIB pure_quanta_power
J 0
(-4925 5375);
DISPLAY INVISIBLE (-4925 5375);
FORCEPROP 1 LAST PATH I20
J 0
(-4875 5400);
DISPLAY 0.872340 (-4875 5400);
PAINT AQUA (-4875 5400);
DISPLAY INVISIBLE (-4875 5400);
FORCEADD Q_CAP..1
(-5225 5025);
FORCEPROP 1 LAST LOCATION C7510
J 0
(-5175 5125);
DISPLAY 0.787234 (-5175 5125);
PAINT SKYBLUE (-5175 5125);
FORCEPROP 0 LAST $SEC 1
J 0
(-5175 5175);
DISPLAY 0.680851 (-5175 5175);
PAINT MONO (-5175 5175);
DISPLAY INVISIBLE (-5175 5175);
FORCEPROP 0 LAST CDS_SEC 1
J 0
(-5175 5175);
DISPLAY 0.680851 (-5175 5175);
DISPLAY INVISIBLE (-5175 5175);
FORCEPROP 1 LASTPIN (-5225 5125) $PN 1
J 0
(-5215 5105);
DISPLAY 0.787234 (-5215 5105);
PAINT MONO (-5215 5105);
FORCEPROP 1 LASTPIN (-5225 4925) $PN 2
J 0
(-5215 4905);
DISPLAY 0.787234 (-5215 4905);
PAINT MONO (-5215 4905);
FORCEPROP 1 LAST VOLTAGE 10V
J 0
(-5175 5025);
DISPLAY 0.510638 (-5175 5025);
FORCEPROP 1 LAST TOLERANCE 10%
J 0
(-5175 4975);
DISPLAY 0.510638 (-5175 4975);
FORCEPROP 1 LAST VALUE 0.1UF
J 0
(-5175 5075);
DISPLAY 0.510638 (-5175 5075);
FORCEPROP 1 LAST PACK_TYPE C0201
J 0
(-5175 4875);
DISPLAY 0.510638 (-5175 4875);
FORCEPROP 1 LAST MATERIAL X7S
J 0
(-5175 4925);
DISPLAY 0.510638 (-5175 4925);
FORCEPROP 2 LAST CDS_LIB pure_quanta
J 0
(-5225 5025);
DISPLAY INVISIBLE (-5225 5025);
FORCEPROP 1 LAST PATH I21
J 0
(-5175 5175);
DISPLAY 0.978723 (-5175 5175);
PAINT WHITE (-5175 5175);
DISPLAY INVISIBLE (-5175 5175);
FORCEPROP 1 LAST PART_NUMBER CH4102K6E00
J 0
(-5175 4875);
DISPLAY 0.978723 (-5175 4875);
DISPLAY INVISIBLE (-5175 4875);
FORCEADD UNIVERSAL_GND..1
(-5225 4750);
FORCEPROP 3 LASTPIN (-5225 4800) SIG_NAME GND\g
J 0
(-5215 4810);
DISPLAY 0.659574 (-5215 4810);
PAINT MONO (-5215 4810);
DISPLAY INVISIBLE (-5215 4810);
FORCEPROP 2 LAST CDS_LIB pure_quanta_power
J 0
(-5225 4750);
DISPLAY INVISIBLE (-5225 4750);
FORCEPROP 1 LAST HDL_POWER GND
J 1
(-5200 4675);
DISPLAY 0.872340 (-5200 4675);
PAINT GREEN (-5200 4675);
DISPLAY INVISIBLE (-5200 4675);
FORCEPROP 1 LAST PATH I22
J 0
(-5150 4750);
DISPLAY 0.872340 (-5150 4750);
PAINT AQUA (-5150 4750);
DISPLAY INVISIBLE (-5150 4750);
FORCEADD UNIVERSAL_GND..1
R 7
(-4900 4575);
FORCEPROP 3 LASTPIN (-4850 4575) SIG_NAME GND\g
J 0
(-4840 4585);
DISPLAY 0.659574 (-4840 4585);
PAINT MONO (-4840 4585);
DISPLAY INVISIBLE (-4840 4585);
FORCEPROP 2 LAST CDS_LIB pure_quanta_power
J 0
(-4900 4575);
DISPLAY INVISIBLE (-4900 4575);
FORCEPROP 1 LAST HDL_POWER GND
R 1
J 1
(-4975 4600);
DISPLAY 0.872340 (-4975 4600);
PAINT GREEN (-4975 4600);
DISPLAY INVISIBLE (-4975 4600);
FORCEPROP 1 LAST PATH I23
R 1
J 0
(-4900 4650);
DISPLAY 0.872340 (-4900 4650);
PAINT AQUA (-4900 4650);
DISPLAY INVISIBLE (-4900 4650);
FORCEADD Q_RES..2
(-3750 4375);
FORCEPROP 1 LAST LOCATION R6822
J 0
(-3705 4500);
DISPLAY 0.978723 (-3705 4500);
FORCEPROP 0 LAST $SEC 1
J 0
(-3700 4550);
DISPLAY 0.680851 (-3700 4550);
PAINT MONO (-3700 4550);
DISPLAY INVISIBLE (-3700 4550);
FORCEPROP 0 LAST CDS_SEC 1
J 0
(-3700 4550);
DISPLAY 0.680851 (-3700 4550);
DISPLAY INVISIBLE (-3700 4550);
FORCEPROP 1 LASTPIN (-3750 4475) $PN 1
J 0
(-3745 4437);
DISPLAY 0.787234 (-3745 4437);
PAINT MONO (-3745 4437);
FORCEPROP 1 LASTPIN (-3750 4275) $PN 2
J 0
(-3745 4285);
DISPLAY 0.787234 (-3745 4285);
PAINT MONO (-3745 4285);
FORCEPROP 1 LAST VALUE 1K
J 0
(-3705 4450);
DISPLAY 0.978723 (-3705 4450);
FORCEPROP 1 LAST WATTAGE 1/20W
J 0
(-3710 4350);
DISPLAY 0.978723 (-3710 4350);
FORCEPROP 1 LAST TOLERANCE 1%
J 0
(-3705 4400);
DISPLAY 0.978723 (-3705 4400);
FORCEPROP 1 LAST MATERIAL CHIP
J 0
(-3710 4300);
DISPLAY 0.978723 (-3710 4300);
FORCEPROP 1 LAST PACK_TYPE 0201LF
J 0
(-3710 4200);
DISPLAY 0.978723 (-3710 4200);
FORCEPROP 2 LAST CDS_LIB pure_quanta
J 0
(-3750 4375);
DISPLAY INVISIBLE (-3750 4375);
FORCEPROP 1 LAST PATH I24
J 0
(-3700 4550);
DISPLAY 0.978723 (-3700 4550);
PAINT WHITE (-3700 4550);
DISPLAY INVISIBLE (-3700 4550);
FORCEPROP 1 LAST PART_NUMBER CS21001FE07
J 0
(-3710 4250);
DISPLAY 0.978723 (-3710 4250);
DISPLAY INVISIBLE (-3710 4250);
FORCEADD UNIVERSAL_GND..1
(-3900 4300);
FORCEPROP 3 LASTPIN (-3900 4350) SIG_NAME GND\g
J 0
(-3890 4360);
DISPLAY 0.659574 (-3890 4360);
PAINT MONO (-3890 4360);
DISPLAY INVISIBLE (-3890 4360);
FORCEPROP 2 LAST CDS_LIB pure_quanta_power
J 0
(-3900 4300);
DISPLAY INVISIBLE (-3900 4300);
FORCEPROP 1 LAST HDL_POWER GND
J 1
(-3875 4225);
DISPLAY 0.872340 (-3875 4225);
PAINT GREEN (-3875 4225);
DISPLAY INVISIBLE (-3875 4225);
FORCEPROP 1 LAST PATH I25
J 0
(-3825 4300);
DISPLAY 0.872340 (-3825 4300);
PAINT AQUA (-3825 4300);
DISPLAY INVISIBLE (-3825 4300);
FORCEADD UNIVERSAL_GND..1
(-3750 3950);
FORCEPROP 3 LASTPIN (-3750 4000) SIG_NAME GND\g
J 0
(-3740 4010);
DISPLAY 0.659574 (-3740 4010);
PAINT MONO (-3740 4010);
DISPLAY INVISIBLE (-3740 4010);
FORCEPROP 2 LAST CDS_LIB pure_quanta_power
J 0
(-3750 3950);
DISPLAY INVISIBLE (-3750 3950);
FORCEPROP 1 LAST HDL_POWER GND
J 1
(-3725 3875);
DISPLAY 0.872340 (-3725 3875);
PAINT GREEN (-3725 3875);
DISPLAY INVISIBLE (-3725 3875);
FORCEPROP 1 LAST PATH I26
J 0
(-3675 3950);
DISPLAY 0.872340 (-3675 3950);
PAINT AQUA (-3675 3950);
DISPLAY INVISIBLE (-3675 3950);
FORCEADD M24M02DRMN6TP..1
(-4425 4550);
FORCEPROP 1 LAST LOCATION U11
J 0
(-4619 4890);
DISPLAY 0.723404 (-4619 4890);
PAINT GREEN (-4619 4890);
FORCEPROP 0 LAST $SEC 1
J 0
(-4600 5025);
DISPLAY 0.680851 (-4600 5025);
PAINT MONO (-4600 5025);
DISPLAY INVISIBLE (-4600 5025);
FORCEPROP 0 LAST CDS_SEC 1
J 0
(-4600 5025);
DISPLAY 0.680851 (-4600 5025);
DISPLAY INVISIBLE (-4600 5025);
FORCEPROP 0 LASTPIN (-4100 4625) $PN 1
J 0
(-4090 4635);
DISPLAY 0.680851 (-4090 4635);
PAINT MONO (-4090 4635);
FORCEPROP 0 LASTPIN (-4100 4575) $PN 2
J 0
(-4090 4585);
DISPLAY 0.680851 (-4090 4585);
PAINT MONO (-4090 4585);
FORCEPROP 0 LASTPIN (-4100 4525) $PN 3
J 0
(-4090 4535);
DISPLAY 0.680851 (-4090 4535);
PAINT MONO (-4090 4535);
FORCEPROP 0 LASTPIN (-4750 4525) $PN 6
J 2
(-4760 4535);
DISPLAY 0.680851 (-4760 4535);
PAINT MONO (-4760 4535);
FORCEPROP 0 LASTPIN (-4750 4475) $PN 5
J 2
(-4760 4485);
DISPLAY 0.680851 (-4760 4485);
PAINT MONO (-4760 4485);
FORCEPROP 0 LASTPIN (-4750 4625) $PN 8
J 2
(-4760 4635);
DISPLAY 0.680851 (-4760 4635);
PAINT MONO (-4760 4635);
FORCEPROP 0 LASTPIN (-4100 4475) $PN 4
J 0
(-4090 4485);
DISPLAY 0.680851 (-4090 4485);
PAINT MONO (-4090 4485);
FORCEPROP 0 LASTPIN (-4750 4575) $PN 7
J 2
(-4760 4585);
DISPLAY 0.680851 (-4760 4585);
PAINT MONO (-4760 4585);
FORCEPROP 1 LAST MATERIAL IC
J 0
(-4619 4682);
DISPLAY 0.723404 (-4619 4682);
PAINT GREEN (-4619 4682);
FORCEPROP 2 LAST PART_TYPE SMLF
J 0
(-4600 4975);
DISPLAY 0.680851 (-4600 4975);
FORCEPROP 2 LAST VALUE M24M02-DRMN6TP
J 0
(-4600 4925);
DISPLAY 0.680851 (-4600 4925);
FORCEPROP 1 LAST NEEDS_NO_SIZE TRUE
J 0
(-4250 4482);
DISPLAY 0.723404 (-4250 4482);
PAINT GREEN (-4250 4482);
DISPLAY INVISIBLE (-4250 4482);
FORCEPROP 1 LAST CDS_LMAN_SYM_OUTLINE -175,125,175,-125
J 0
(-4425 4550);
DISPLAY 0.468085 (-4425 4550);
PAINT GREEN (-4425 4550);
DISPLAY INVISIBLE (-4425 4550);
FORCEPROP 2 LAST CDS_LIB pure_quanta
J 0
(-4425 4550);
DISPLAY INVISIBLE (-4425 4550);
FORCEPROP 1 LAST PATH I3
J 0
(-4250 4425);
DISPLAY 0.723404 (-4250 4425);
PAINT GREEN (-4250 4425);
DISPLAY INVISIBLE (-4250 4425);
FORCEPROP 1 LAST PART_NUMBER AKE33Z00600
J 0
(-4619 4776);
DISPLAY 0.723404 (-4619 4776);
PAINT GREEN (-4619 4776);
DISPLAY INVISIBLE (-4619 4776);
FORCEADD OFFPAGE..1
(-7075 4525);
FORCEPROP 2 LAST $XR1 186 
J 0
(-7447 4525);
DISPLAY 0.638298 (-7447 4525);
PAINT MONO (-7447 4525);
FORCEPROP 2 LAST $XR0 185 
J 0
(-7327 4525);
DISPLAY 0.638298 (-7327 4525);
PAINT MONO (-7327 4525);
FORCEPROP 2 LAST CDS_LIB standard
J 0
(-7075 4525);
DISPLAY INVISIBLE (-7075 4525);
FORCEPROP 1 LAST OFFPAGE TRUE
J 0
(-6750 4400);
DISPLAY 0.872340 (-6750 4400);
DISPLAY INVISIBLE (-6750 4400);
FORCEPROP 1 LAST COMMENT_BODY TRUE
J 0
(-6950 4425);
DISPLAY 0.872340 (-6950 4425);
PAINT GREEN (-6950 4425);
DISPLAY INVISIBLE (-6950 4425);
FORCEPROP 2 LAST PATH I4
J 0
(-7025 4600);
DISPLAY 0.680851 (-7025 4600);
DISPLAY INVISIBLE (-7025 4600);
FORCEADD OFFPAGE..3
R 2
(-7050 4475);
FORCEPROP 2 LAST $XR1 186 
J 0
(-7480 4475);
DISPLAY 0.638298 (-7480 4475);
PAINT MONO (-7480 4475);
FORCEPROP 2 LAST $XR0 185 
J 0
(-7360 4475);
DISPLAY 0.638298 (-7360 4475);
PAINT MONO (-7360 4475);
FORCEPROP 2 LAST CDS_LIB standard
J 0
(-7050 4475);
DISPLAY INVISIBLE (-7050 4475);
FORCEPROP 1 LAST OFFPAGE TRUE
J 2
(-7375 4350);
DISPLAY 0.872340 (-7375 4350);
PAINT GREEN (-7375 4350);
DISPLAY INVISIBLE (-7375 4350);
FORCEPROP 1 LAST COMMENT_BODY TRUE
J 2
(-7000 4375);
DISPLAY 0.872340 (-7000 4375);
PAINT GREEN (-7000 4375);
DISPLAY INVISIBLE (-7000 4375);
FORCEPROP 2 LAST PATH I5
J 0
(-7000 4550);
DISPLAY 0.680851 (-7000 4550);
DISPLAY INVISIBLE (-7000 4550);
FORCEADD Q_RES..1
(-5850 4525);
FORCEPROP 1 LAST LOCATION R668
J 0
(-6100 4525);
DISPLAY 0.978723 (-6100 4525);
FORCEPROP 0 LAST $SEC 1
J 0
(-5975 4675);
DISPLAY 0.680851 (-5975 4675);
PAINT MONO (-5975 4675);
DISPLAY INVISIBLE (-5975 4675);
FORCEPROP 0 LAST CDS_SEC 1
J 0
(-5975 4675);
DISPLAY 0.680851 (-5975 4675);
DISPLAY INVISIBLE (-5975 4675);
FORCEPROP 1 LASTPIN (-5950 4525) $PN 1
J 0
(-5938 4537);
DISPLAY 0.787234 (-5938 4537);
PAINT MONO (-5938 4537);
FORCEPROP 1 LASTPIN (-5750 4525) $PN 2
J 0
(-5788 4537);
DISPLAY 0.787234 (-5788 4537);
PAINT MONO (-5788 4537);
FORCEPROP 1 LAST PACK_TYPE 0201LF
J 0
(-5850 4575);
DISPLAY 0.638298 (-5850 4575);
FORCEPROP 1 LAST MATERIAL CHIP
J 0
(-6000 4575);
DISPLAY 0.638298 (-6000 4575);
FORCEPROP 1 LAST WATTAGE 1/20W
J 2
(-6025 4575);
DISPLAY 0.638298 (-6025 4575);
FORCEPROP 1 LAST VALUE 33.2
J 2
(-6125 4625);
DISPLAY 0.638298 (-6125 4625);
FORCEPROP 1 LAST TOLERANCE 1%
J 0
(-6100 4625);
DISPLAY 0.638298 (-6100 4625);
FORCEPROP 2 LAST CDS_LIB pure_quanta
J 0
(-5850 4525);
DISPLAY INVISIBLE (-5850 4525);
FORCEPROP 1 LAST PATH I6
J 0
(-5900 4675);
DISPLAY 0.978723 (-5900 4675);
PAINT WHITE (-5900 4675);
DISPLAY INVISIBLE (-5900 4675);
FORCEPROP 1 LAST PART_NUMBER CS03321FE09
J 0
(-5975 4625);
DISPLAY 0.638298 (-5975 4625);
DISPLAY INVISIBLE (-5975 4625);
FORCEADD Q_RES..1
(-5850 4475);
FORCEPROP 1 LAST LOCATION R669
J 0
(-6100 4475);
DISPLAY 0.978723 (-6100 4475);
FORCEPROP 0 LAST $SEC 1
J 0
(-6100 4525);
DISPLAY 0.680851 (-6100 4525);
PAINT MONO (-6100 4525);
DISPLAY INVISIBLE (-6100 4525);
FORCEPROP 0 LAST CDS_SEC 1
J 0
(-6100 4525);
DISPLAY 0.680851 (-6100 4525);
DISPLAY INVISIBLE (-6100 4525);
FORCEPROP 1 LASTPIN (-5950 4475) $PN 1
J 0
(-5938 4487);
DISPLAY 0.787234 (-5938 4487);
PAINT MONO (-5938 4487);
FORCEPROP 1 LASTPIN (-5750 4475) $PN 2
J 0
(-5788 4487);
DISPLAY 0.787234 (-5788 4487);
PAINT MONO (-5788 4487);
FORCEPROP 2 LAST CDS_LIB pure_quanta
J 0
(-5850 4475);
DISPLAY INVISIBLE (-5850 4475);
FORCEPROP 1 LAST MATERIAL CHIP
J 0
(-6025 4525);
DISPLAY 0.787234 (-6025 4525);
DISPLAY INVISIBLE (-6025 4525);
FORCEPROP 1 LAST WATTAGE 1/20W
J 2
(-6025 4525);
DISPLAY 0.787234 (-6025 4525);
DISPLAY INVISIBLE (-6025 4525);
FORCEPROP 1 LAST PACK_TYPE 0201LF
J 0
(-5800 4525);
DISPLAY 0.787234 (-5800 4525);
DISPLAY INVISIBLE (-5800 4525);
FORCEPROP 1 LAST VALUE 33.2
J 2
(-6125 4575);
DISPLAY 0.787234 (-6125 4575);
DISPLAY INVISIBLE (-6125 4575);
FORCEPROP 1 LAST TOLERANCE 1%
J 0
(-6100 4575);
DISPLAY 0.787234 (-6100 4575);
DISPLAY INVISIBLE (-6100 4575);
FORCEPROP 1 LAST PATH I7
J 0
(-5900 4625);
DISPLAY 0.978723 (-5900 4625);
PAINT WHITE (-5900 4625);
DISPLAY INVISIBLE (-5900 4625);
FORCEPROP 1 LAST PART_NUMBER CS03321FE09
J 0
(-5975 4575);
DISPLAY 0.787234 (-5975 4575);
DISPLAY INVISIBLE (-5975 4575);
FORCEADD QUANTA_TITLE_BLOCK_C..1
(0 0);
FORCEPROP 0 LAST CDS_CON_LAST_MODIFIED Thu Sep 14 16:12:59 2023
J 0
(-1885 15);
DISPLAY INVISIBLE (-1885 15);
FORCEPROP 1 LAST CUSTOM_TXT_CDS <CON_LAST_MODIFIED>
J 0
(-1885 15);
DISPLAY 0.978723 (-1885 15);
FORCEPROP 2 LAST CUSTOM_TXT_CDS <XR_PAGE_TITLE>
J 0
(-7890 5250);
DISPLAY 0.638298 (-7890 5250);
PAINT PINK (-7890 5250);
DISPLAY INVISIBLE (-7890 5250);
FORCEPROP 1 LAST CUSTOM_TXT_CDS <NAME_2>
J 0
(-3175 50);
FORCEPROP 1 LAST CUSTOM_TXT_CDS <NAME_1>
J 0
(-3175 175);
FORCEPROP 1 LAST CUSTOM_TXT_CDS <Q_NUMBER>
J 0
(-1403 103);
DISPLAY 1.212766 (-1403 103);
FORCEPROP 1 LAST CUSTOM_TXT_CDS <Q_PROJ>
J 0
(-2382 102);
DISPLAY 1.212766 (-2382 102);
FORCEPROP 1 LAST CUSTOM_TXT_CDS <Q_REV>
J 0
(-184 103);
DISPLAY 1.212766 (-184 103);
FORCEPROP 1 LAST CUSTOM_TXT_CDS <CON_PAGE_NUM> OF <CON_TOTAL_PAGES>
J 0
(-446 18);
DISPLAY 0.978723 (-446 18);
FORCEPROP 1 LAST Q_TITLE RETIMER_CPU0_P0(7)
J 0
(-9366 26);
DISPLAY 2.446809 (-9366 26);
PAINT GREEN (-9366 26);
FORCEPROP 2 LAST CDS_LIB pure_quanta
J 0
(0 0);
DISPLAY INVISIBLE (0 0);
FORCEPROP 1 LAST CDS_LMAN_SYM_OUTLINE -9475,6775,100,-125
J 0
(0 0);
DISPLAY 0.468085 (0 0);
PAINT GREEN (0 0);
DISPLAY INVISIBLE (0 0);
FORCEPROP 2 LAST PAGE_BORDER TRUE
J 0
(-7890 5250);
DISPLAY 0.638298 (-7890 5250);
PAINT PINK (-7890 5250);
DISPLAY INVISIBLE (-7890 5250);
FORCEPROP 2 LAST CDS_XR_PAGE_TITLE CR-279 : @T6G_MB_LIB.T6G(SCH_1):PAGE279
J 0
(-7890 5250);
DISPLAY 0.638298 (-7890 5250);
PAINT PINK (-7890 5250);
DISPLAY INVISIBLE (-7890 5250);
FORCEPROP 1 LAST Q_DEPT BU9
J 1
(-3763 49);
DISPLAY 1.957447 (-3763 49);
PAINT GREEN (-3763 49);
DISPLAY INVISIBLE (-3763 49);
FORCEPROP 1 LAST COMMENT_BODY TRUE
J 0
(12 -13);
DISPLAY 0.978723 (12 -13);
PAINT GREEN (12 -13);
DISPLAY INVISIBLE (12 -13);
WIRE 16 -1 (-5225 4925)(-5225 4800);
WIRE 16 -1 (-4750 4575)(-4850 4575);
WIRE 16 -1 (-4100 4475)(-3900 4475);
WIRE 16 -1 (-3900 4475)(-3900 4350);
WIRE 16 -1 (-3750 4275)(-3750 4000);
WIRE 16 -1 (-5950 4475)(-7000 4475);
FORCEPROP 2 LAST SIG_NAME SMB_RT_CPU0_P0_ROM_R_SDA
J 0
(-6910 4485);
DISPLAY 0.680851 (-6910 4485);
WIRE 16 -1 (-4750 4475)(-5750 4475);
FORCEPROP 2 LAST SIG_NAME SMB_RT_CPU0_P0_ROM_SDA
J 0
(-5635 4485);
DISPLAY 0.680851 (-5635 4485);
FORCEPROP 2 LASTPROP $XRERR UNIQUE?
J 0
(-5875 4485);
DISPLAY 0.638298 (-5875 4485);
PAINT MONO (-5875 4485);
DISPLAY INVISIBLE (-5875 4485);
WIRE 16 -1 (-5950 4525)(-7025 4525);
FORCEPROP 2 LAST SIG_NAME SMB_RT_CPU0_P0_ROM_R_SCL
J 0
(-6910 4535);
DISPLAY 0.680851 (-6910 4535);
WIRE 16 -1 (-4750 4525)(-5750 4525);
FORCEPROP 2 LAST SIG_NAME SMB_RT_CPU0_P0_ROM_SCL
J 0
(-5635 4535);
DISPLAY 0.680851 (-5635 4535);
FORCEPROP 2 LASTPROP $XRERR UNIQUE?
J 0
(-5875 4535);
DISPLAY 0.638298 (-5875 4535);
PAINT MONO (-5875 4535);
DISPLAY INVISIBLE (-5875 4535);
WIRE 16 -1 (-4925 5325)(-4925 5250);
WIRE 16 -1 (-4925 5250)(-4925 4625);
WIRE 16 -1 (-5225 5250)(-4925 5250);
WIRE 16 -1 (-5225 5125)(-5225 5250);
WIRE 16 -1 (-4925 4625)(-4750 4625);
WIRE 16 -1 (-4100 4525)(-3750 4525);
FORCEPROP 2 LAST SIG_NAME U11_E2
J 0
(-3960 4535);
DISPLAY 0.680851 (-3960 4535);
FORCEPROP 2 LASTPROP $XRERR UNIQUE?
J 0
(-4200 4535);
DISPLAY 0.638298 (-4200 4535);
PAINT MONO (-4200 4535);
DISPLAY INVISIBLE (-4200 4535);
WIRE 16 -1 (-3750 4525)(-3750 4475);
DOT 1 (-4925 5250);
FORCENOTE
RETIMER EEPRO ADDRESS: 0XA0 (8 BIT) / 0X50 (7 BIT)
(-7900 4175) 0;
DISPLAY LEFT (-7900 4175);
DISPLAY 1.595745 (-7900 4175);
QUIT
